# T6G (Grand Teton) — schematic netlist excerpt (pin names and nets, part order shuffled) for the footprints in the layout excerpt that follows; sources: Cadence DE-HDL packaged netlist, KiCad conversion of 04192023_DAF0TMB3IC0_F0TG_MB_C_brd_V02_OCP.brd

PR269  Q_RES  0 5% CHIP  pkg 0402LF  page 219 : A = PVDDCR_CPU1_P1_VOS3 ; B = PVDDCR_CPU1_P1
PC2344  Q_CAP  22UF 16V 20% X6S  pkg C0805  page 190 : A = SW_P3V3_AUX_FLT ; B = GND
C2075  Q_CAP_DIFFBUS  DIFF BUS_0.22UF 6.3V 20% X6S  pkg C0201  page 53 : \1\ = P3E_CPU1_P5_TX_C_DP<0> ; \2\ = P3E_CPU1_P5_TX_DP<0>

(kicad_pcb
	(version 20260206)
	(generator "pcbnew")
	(generator_version "10.0")
	(general
		(thickness 1.6)
		(legacy_teardrops no)
	)
	(paper "A4")
	(title_block
		(title "04192023_DAF0TMB3IC0_F0TG_MB_C_brd_V02_OCP.brd")
		(comment 1 "Grand Teton / footprints 6650-6652 of 8354")
	)
	(layers
		(0 "F.Cu" signal "TOP")
		(4 "In1.Cu" signal "GND")
		(6 "In2.Cu" signal "IN1")
		(8 "In3.Cu" signal "GND1")
		(10 "In4.Cu" signal "IN2")
		(12 "In5.Cu" signal "GND2")
		(14 "In6.Cu" signal "IN3")
		(16 "In7.Cu" signal "GND3")
		(18 "In8.Cu" signal "VCC")
		(20 "In9.Cu" signal "VCC1")
		(22 "In10.Cu" signal "GND4")
		(24 "In11.Cu" signal "IN4")
		(26 "In12.Cu" signal "GND5")
		(28 "In13.Cu" signal "IN5")
		(30 "In14.Cu" signal "GND6")
		(32 "In15.Cu" signal "IN6")
		(34 "In16.Cu" signal "GND7")
		(2 "B.Cu" signal "BOTTOM")
		(9 "F.Adhes" user "F.Adhesive")
		(11 "B.Adhes" user "B.Adhesive")
		(13 "F.Paste" user "Package Geometry/Pastemask Top")
		(15 "B.Paste" user "Package Geometry/Pastemask Bottom")
		(5 "F.SilkS" user "Ref Des/Silkscreen Top")
		(7 "B.SilkS" user "Ref Des/Silkscreen Bottom")
		(1 "F.Mask" user "Board Geometry/Soldermask Top")
		(3 "B.Mask" user "Board Geometry/Soldermask Bottom")
		(17 "Dwgs.User" user "User.Drawings")
		(19 "Cmts.User" user "User.Comments")
		(21 "Eco1.User" user "User.Eco1")
		(23 "Eco2.User" user "User.Eco2")
		(25 "Edge.Cuts" user "Board Geometry/Outline")
		(27 "Margin" user)
		(31 "F.CrtYd" user "Package Geometry/Place Bound Top")
		(29 "B.CrtYd" user "Package Geometry/Place Bound Bottom")
		(35 "F.Fab" user "Ref Des/Assembly Top")
		(33 "B.Fab" user "Ref Des/Assembly Bottom")
	)
	(footprint ""
		(layer "B.Cu")
		(at 66.747644 -337.665314 -90)
		(property "Reference" "PR269"
			(at 0 0 90)
			(layer "B.SilkS")
			(hide yes)
			(effects
				(font
					(size 1.27 1.27)
				)
				(justify mirror)
			)
		)
		(property "Value" ""
			(at 0 0 90)
			(layer "B.Fab")
			(effects
				(font
					(size 1.27 1.27)
				)
				(justify mirror)
			)
		)
		(duplicate_pad_numbers_are_jumpers no)
		(fp_line
			(start -0.7874 0.4064)
			(end 0.7874 0.4064)
			(stroke
				(width 0.1524)
				(type default)
			)
			(layer "B.SilkS")
		)
		(fp_line
			(start 0.7874 0.4064)
			(end 0.7874 -0.4064)
			(stroke
				(width 0.1524)
				(type default)
			)
			(layer "B.SilkS")
		)
		(fp_line
			(start -0.7874 -0.4064)
			(end -0.7874 0.4064)
			(stroke
				(width 0.1524)
				(type default)
			)
			(layer "B.SilkS")
		)
		(fp_line
			(start 0.7874 -0.4064)
			(end -0.7874 -0.4064)
			(stroke
				(width 0.1524)
				(type default)
			)
			(layer "B.SilkS")
		)
		(fp_line
			(start -0.67945 0.3048)
			(end -0.120396 0.3048)
			(stroke
				(width 0.1)
				(type default)
			)
			(layer "B.Fab")
		)
		(fp_line
			(start -0.120396 0.3048)
			(end -0.120396 0.2794)
			(stroke
				(width 0.1)
				(type default)
			)
			(layer "B.Fab")
		)
		(fp_line
			(start 0.12065 0.3048)
			(end 0.67945 0.3048)
			(stroke
				(width 0.1)
				(type default)
			)
			(layer "B.Fab")
		)
		(fp_line
			(start 0.67945 0.3048)
			(end 0.67945 -0.305054)
			(stroke
				(width 0.1)
				(type default)
			)
			(layer "B.Fab")
		)
		(fp_line
			(start -0.120396 0.2794)
			(end 0.12065 0.2794)
			(stroke
				(width 0.1)
				(type default)
			)
			(layer "B.Fab")
		)
		(fp_line
			(start 0.12065 0.2794)
			(end 0.12065 0.3048)
			(stroke
				(width 0.1)
				(type default)
			)
			(layer "B.Fab")
		)
		(fp_line
			(start -0.12065 -0.2794)
			(end -0.12065 -0.3048)
			(stroke
				(width 0.1)
				(type default)
			)
			(layer "B.Fab")
		)
		(fp_line
			(start 0.12065 -0.2794)
			(end -0.12065 -0.2794)
			(stroke
				(width 0.1)
				(type default)
			)
			(layer "B.Fab")
		)
		(fp_line
			(start -0.67945 -0.3048)
			(end -0.67945 0.3048)
			(stroke
				(width 0.1)
				(type default)
			)
			(layer "B.Fab")
		)
		(fp_line
			(start -0.12065 -0.3048)
			(end -0.67945 -0.3048)
			(stroke
				(width 0.1)
				(type default)
			)
			(layer "B.Fab")
		)
		(fp_line
			(start 0.12065 -0.305054)
			(end 0.12065 -0.2794)
			(stroke
				(width 0.1)
				(type default)
			)
			(layer "B.Fab")
		)
		(fp_line
			(start 0.67945 -0.305054)
			(end 0.12065 -0.305054)
			(stroke
				(width 0.1)
				(type default)
			)
			(layer "B.Fab")
		)
		(pad "1" smd circle
			(at 0.40005 0 90)
			(size 0 0)
			(layers "B.Cu" "B.Mask" "B.Paste")
			(net "PVDDCR_CPU1_P1_VOS3")
		)
		(pad "2" smd circle
			(at -0.40005 0 90)
			(size 0 0)
			(layers "B.Cu" "B.Mask" "B.Paste")
			(net "PVDDCR_CPU1_P1")
		)
	)
	(footprint ""
		(layer "B.Cu")
		(at 51.734974 -416.091116)
		(property "Reference" "C2075"
			(at 0 0 0)
			(layer "B.SilkS")
			(hide yes)
			(effects
				(font
					(size 1.27 1.27)
				)
				(justify mirror)
			)
		)
		(property "Value" ""
			(at 0 0 0)
			(layer "B.Fab")
			(effects
				(font
					(size 1.27 1.27)
				)
				(justify mirror)
			)
		)
		(duplicate_pad_numbers_are_jumpers no)
		(fp_line
			(start -0.299974 -0.150114)
			(end -0.299974 0.150114)
			(stroke
				(width 0.1)
				(type default)
			)
			(layer "B.Fab")
		)
		(fp_line
			(start -0.299974 0.150114)
			(end 0.299974 0.150114)
			(stroke
				(width 0.1)
				(type default)
			)
			(layer "B.Fab")
		)
		(fp_line
			(start 0.299974 -0.150114)
			(end -0.299974 -0.150114)
			(stroke
				(width 0.1)
				(type default)
			)
			(layer "B.Fab")
		)
		(fp_line
			(start 0.299974 0.150114)
			(end 0.299974 -0.150114)
			(stroke
				(width 0.1)
				(type default)
			)
			(layer "B.Fab")
		)
		(pad "1" smd rect
			(at 0.2667 0 180)
			(size 0.3048 0.381)
			(layers "B.Cu" "B.Mask" "B.Paste")
			(net "P3E_CPU1_P5_TX_C_DP<0>")
		)
		(pad "2" smd rect
			(at -0.2667 0 180)
			(size 0.3048 0.381)
			(layers "B.Cu" "B.Mask" "B.Paste")
			(net "P3E_CPU1_P5_TX_DP<0>")
		)
	)
	(footprint ""
		(layer "B.Cu")
		(at 450.177916 -47.505366 90)
		(property "Reference" "PC2344"
			(at 0 0 90)
			(layer "B.SilkS")
			(hide yes)
			(effects
				(font
					(size 1.27 1.27)
				)
				(justify mirror)
			)
		)
		(property "Value" ""
			(at 0 0 90)
			(layer "B.Fab")
			(effects
				(font
					(size 1.27 1.27)
				)
				(justify mirror)
			)
		)
		(duplicate_pad_numbers_are_jumpers no)
		(fp_line
			(start 1.524 -0.762)
			(end -1.524 -0.762)
			(stroke
				(width 0.1524)
				(type default)
			)
			(layer "B.SilkS")
		)
		(fp_line
			(start -1.524 -0.762)
			(end -1.524 0.762)
			(stroke
				(width 0.1524)
				(type default)
			)
			(layer "B.SilkS")
		)
		(fp_line
			(start 1.524 0.762)
			(end 1.524 -0.762)
			(stroke
				(width 0.1524)
				(type default)
			)
			(layer "B.SilkS")
		)
		(fp_line
			(start -1.524 0.762)
			(end 1.524 0.762)
			(stroke
				(width 0.1524)
				(type default)
			)
			(layer "B.SilkS")
		)
		(fp_line
			(start 1.1049 -0.724916)
			(end 1.1049 0.724916)
			(stroke
				(width 0.1)
				(type default)
			)
			(layer "B.Fab")
		)
		(fp_line
			(start -1.1049 -0.724916)
			(end 1.1049 -0.724916)
			(stroke
				(width 0.1)
				(type default)
			)
			(layer "B.Fab")
		)
		(fp_line
			(start 1.1049 0.724916)
			(end -1.1049 0.724916)
			(stroke
				(width 0.1)
				(type default)
			)
			(layer "B.Fab")
		)
		(fp_line
			(start -1.1049 0.724916)
			(end -1.1049 -0.724916)
			(stroke
				(width 0.1)
				(type default)
			)
			(layer "B.Fab")
		)
		(pad "1" smd rect
			(at 0.889 0 90)
			(size 1.016 1.27)
			(layers "B.Cu" "B.Mask" "B.Paste")
			(net "SW_P3V3_AUX_FLT")
		)
		(pad "2" smd rect
			(at -0.889 0 90)
			(size 1.016 1.27)
			(layers "B.Cu" "B.Mask" "B.Paste")
			(net "GND")
		)
	)
)
